(kicad_pcb
	(version 20260206)
	(generator "pcbnew")
	(generator_version "10.0")
	(general
		(thickness 1.6)
		(legacy_teardrops no)
	)
	(paper "A4")
	(title_block
		(title "03242023_DA0F0TMBIJ0_F0T_Motherboard_J_brd_V01_OCP.brd")
		(comment 1 "Grand Teton / footprints 5789-5793 of 6105")
	)
	(layers
		(0 "F.Cu" signal "TOP")
		(4 "In1.Cu" signal "GND")
		(6 "In2.Cu" signal "IN1")
		(8 "In3.Cu" signal "GND1")
		(10 "In4.Cu" signal "IN2")
		(12 "In5.Cu" signal "GND2")
		(14 "In6.Cu" signal "IN3")
		(16 "In7.Cu" signal "GND3")
		(18 "In8.Cu" signal "VCC")
		(20 "In9.Cu" signal "VCC1")
		(22 "In10.Cu" signal "GND4")
		(24 "In11.Cu" signal "IN4")
		(26 "In12.Cu" signal "GND5")
		(28 "In13.Cu" signal "IN5")
		(30 "In14.Cu" signal "GND6")
		(32 "In15.Cu" signal "IN6")
		(34 "In16.Cu" signal "GND7")
		(2 "B.Cu" signal "BOTTOM")
		(9 "F.Adhes" user "F.Adhesive")
		(11 "B.Adhes" user "B.Adhesive")
		(13 "F.Paste" user "Package Geometry/Pastemask Top")
		(15 "B.Paste" user "Package Geometry/Pastemask Bottom")
		(5 "F.SilkS" user "Ref Des/Silkscreen Top")
		(7 "B.SilkS" user "Ref Des/Silkscreen Bottom")
		(1 "F.Mask" user "Board Geometry/Soldermask Top")
		(3 "B.Mask" user "Board Geometry/Soldermask Bottom")
		(17 "Dwgs.User" user "User.Drawings")
		(19 "Cmts.User" user "User.Comments")
		(21 "Eco1.User" user "User.Eco1")
		(23 "Eco2.User" user "User.Eco2")
		(25 "Edge.Cuts" user "Board Geometry/Outline")
		(27 "Margin" user)
		(31 "F.CrtYd" user "Package Geometry/Place Bound Top")
		(29 "B.CrtYd" user "Package Geometry/Place Bound Bottom")
		(35 "F.Fab" user "Ref Des/Assembly Top")
		(33 "B.Fab" user "Ref Des/Assembly Bottom")
	)
	(footprint ""
		(layer "B.Cu")
		(at 320.645282 -26.71064 90)
		(property "Reference" "R622"
			(at 0 0 90)
			(layer "B.SilkS")
			(hide yes)
			(effects
				(font
					(size 1.27 1.27)
				)
				(justify mirror)
			)
		)
		(property "Value" ""
			(at 0 0 90)
			(layer "B.Fab")
			(effects
				(font
					(size 1.27 1.27)
				)
				(justify mirror)
			)
		)
		(duplicate_pad_numbers_are_jumpers no)
		(fp_line
			(start 0.7874 -0.4064)
			(end -0.7874 -0.4064)
			(stroke
				(width 0.1524)
				(type default)
			)
			(layer "B.SilkS")
		)
		(fp_line
			(start -0.7874 -0.4064)
			(end -0.7874 0.4064)
			(stroke
				(width 0.1524)
				(type default)
			)
			(layer "B.SilkS")
		)
		(fp_line
			(start 0.7874 0.4064)
			(end 0.7874 -0.4064)
			(stroke
				(width 0.1524)
				(type default)
			)
			(layer "B.SilkS")
		)
		(fp_line
			(start -0.7874 0.4064)
			(end 0.7874 0.4064)
			(stroke
				(width 0.1524)
				(type default)
			)
			(layer "B.SilkS")
		)
		(fp_line
			(start 0.67945 -0.305054)
			(end 0.12065 -0.305054)
			(stroke
				(width 0.1)
				(type default)
			)
			(layer "B.Fab")
		)
		(fp_line
			(start 0.12065 -0.305054)
			(end 0.12065 -0.2794)
			(stroke
				(width 0.1)
				(type default)
			)
			(layer "B.Fab")
		)
		(fp_line
			(start -0.12065 -0.3048)
			(end -0.67945 -0.3048)
			(stroke
				(width 0.1)
				(type default)
			)
			(layer "B.Fab")
		)
		(fp_line
			(start -0.67945 -0.3048)
			(end -0.67945 0.3048)
			(stroke
				(width 0.1)
				(type default)
			)
			(layer "B.Fab")
		)
		(fp_line
			(start 0.12065 -0.2794)
			(end -0.12065 -0.2794)
			(stroke
				(width 0.1)
				(type default)
			)
			(layer "B.Fab")
		)
		(fp_line
			(start -0.12065 -0.2794)
			(end -0.12065 -0.3048)
			(stroke
				(width 0.1)
				(type default)
			)
			(layer "B.Fab")
		)
		(fp_line
			(start 0.12065 0.2794)
			(end 0.12065 0.3048)
			(stroke
				(width 0.1)
				(type default)
			)
			(layer "B.Fab")
		)
		(fp_line
			(start -0.120396 0.2794)
			(end 0.12065 0.2794)
			(stroke
				(width 0.1)
				(type default)
			)
			(layer "B.Fab")
		)
		(fp_line
			(start 0.67945 0.3048)
			(end 0.67945 -0.305054)
			(stroke
				(width 0.1)
				(type default)
			)
			(layer "B.Fab")
		)
		(fp_line
			(start 0.12065 0.3048)
			(end 0.67945 0.3048)
			(stroke
				(width 0.1)
				(type default)
			)
			(layer "B.Fab")
		)
		(fp_line
			(start -0.120396 0.3048)
			(end -0.120396 0.2794)
			(stroke
				(width 0.1)
				(type default)
			)
			(layer "B.Fab")
		)
		(fp_line
			(start -0.67945 0.3048)
			(end -0.120396 0.3048)
			(stroke
				(width 0.1)
				(type default)
			)
			(layer "B.Fab")
		)
		(pad "1" smd circle
			(at 0.40005 0 270)
			(size 0 0)
			(layers "B.Cu" "B.Mask" "B.Paste")
			(net "FM_PCH_SKIP_RTC_CLOCK")
		)
		(pad "2" smd circle
			(at -0.40005 0 270)
			(size 0 0)
			(layers "B.Cu" "B.Mask" "B.Paste")
			(net "GND")
		)
	)
	(footprint ""
		(layer "B.Cu")
		(at 159.278574 -38.495986)
		(property "Reference" "C2315"
			(at 0 0 0)
			(layer "B.SilkS")
			(hide yes)
			(effects
				(font
					(size 1.27 1.27)
				)
				(justify mirror)
			)
		)
		(property "Value" ""
			(at 0 0 0)
			(layer "B.Fab")
			(effects
				(font
					(size 1.27 1.27)
				)
				(justify mirror)
			)
		)
		(duplicate_pad_numbers_are_jumpers no)
		(fp_line
			(start -0.7874 -0.4064)
			(end -0.7874 0.4064)
			(stroke
				(width 0.1524)
				(type default)
			)
			(layer "B.SilkS")
		)
		(fp_line
			(start -0.7874 0.4064)
			(end 0.7874 0.4064)
			(stroke
				(width 0.1524)
				(type default)
			)
			(layer "B.SilkS")
		)
		(fp_line
			(start 0.7874 -0.4064)
			(end -0.7874 -0.4064)
			(stroke
				(width 0.1524)
				(type default)
			)
			(layer "B.SilkS")
		)
		(fp_line
			(start 0.7874 0.4064)
			(end 0.7874 -0.4064)
			(stroke
				(width 0.1524)
				(type default)
			)
			(layer "B.SilkS")
		)
		(fp_line
			(start -0.67945 -0.3048)
			(end -0.67945 0.3048)
			(stroke
				(width 0.1)
				(type default)
			)
			(layer "B.Fab")
		)
		(fp_line
			(start -0.67945 0.3048)
			(end -0.120396 0.3048)
			(stroke
				(width 0.1)
				(type default)
			)
			(layer "B.Fab")
		)
		(fp_line
			(start -0.12065 -0.3048)
			(end -0.67945 -0.3048)
			(stroke
				(width 0.1)
				(type default)
			)
			(layer "B.Fab")
		)
		(fp_line
			(start -0.12065 -0.2794)
			(end -0.12065 -0.3048)
			(stroke
				(width 0.1)
				(type default)
			)
			(layer "B.Fab")
		)
		(fp_line
			(start -0.120396 0.2794)
			(end 0.12065 0.2794)
			(stroke
				(width 0.1)
				(type default)
			)
			(layer "B.Fab")
		)
		(fp_line
			(start -0.120396 0.3048)
			(end -0.120396 0.2794)
			(stroke
				(width 0.1)
				(type default)
			)
			(layer "B.Fab")
		)
		(fp_line
			(start 0.12065 -0.305054)
			(end 0.12065 -0.2794)
			(stroke
				(width 0.1)
				(type default)
			)
			(layer "B.Fab")
		)
		(fp_line
			(start 0.12065 -0.2794)
			(end -0.12065 -0.2794)
			(stroke
				(width 0.1)
				(type default)
			)
			(layer "B.Fab")
		)
		(fp_line
			(start 0.12065 0.2794)
			(end 0.12065 0.3048)
			(stroke
				(width 0.1)
				(type default)
			)
			(layer "B.Fab")
		)
		(fp_line
			(start 0.12065 0.3048)
			(end 0.67945 0.3048)
			(stroke
				(width 0.1)
				(type default)
			)
			(layer "B.Fab")
		)
		(fp_line
			(start 0.67945 -0.305054)
			(end 0.12065 -0.305054)
			(stroke
				(width 0.1)
				(type default)
			)
			(layer "B.Fab")
		)
		(fp_line
			(start 0.67945 0.3048)
			(end 0.67945 -0.305054)
			(stroke
				(width 0.1)
				(type default)
			)
			(layer "B.Fab")
		)
		(pad "1" smd circle
			(at 0.40005 0 180)
			(size 0 0)
			(layers "B.Cu" "B.Mask" "B.Paste")
			(net "P3V3_AUX_USB_HUB_2")
		)
		(pad "2" smd circle
			(at -0.40005 0 180)
			(size 0 0)
			(layers "B.Cu" "B.Mask" "B.Paste")
			(net "GND")
		)
	)
	(footprint ""
		(layer "B.Cu")
		(at 482.66985 2.372868 90)
		(property "Reference" "X24"
			(at 1.354328 3.30454 270)
			(unlocked yes)
			(layer "B.SilkS")
			(effects
				(font
					(size 0.7874 0.5842)
					(thickness 0.1524)
				)
				(justify left mirror)
			)
		)
		(property "Value" ""
			(at 0 0 90)
			(layer "B.Fab")
			(effects
				(font
					(size 1.27 1.27)
				)
				(justify mirror)
			)
		)
		(property "Device Type" "TP_TDR_4P_FTS_MPKT4_H025P0200_I"
			(at -1.30175 1.27 0)
			(unlocked yes)
			(layer "B.Fab")
			(hide yes)
			(effects
				(font
					(size 0.635 0.4064)
					(thickness 0.1524)
				)
				(justify mirror)
			)
		)
		(property "User Part Number" "TP15"
			(at -1.30175 1.27 0)
			(unlocked yes)
			(layer "Cmts.User")
			(hide yes)
			(effects
				(font
					(size 0.635 0.4064)
					(thickness 0.1524)
				)
				(justify mirror)
			)
		)
		(duplicate_pad_numbers_are_jumpers no)
		(fp_line
			(start 0 -1.27)
			(end 0 -0.635)
			(stroke
				(width 0.1524)
				(type default)
			)
			(layer "B.SilkS")
		)
		(fp_line
			(start -2.54 -1.27)
			(end 0 -1.27)
			(stroke
				(width 0.1524)
				(type default)
			)
			(layer "B.SilkS")
		)
		(fp_line
			(start -2.54 -1.1303)
			(end -2.54 -1.27)
			(stroke
				(width 0.1524)
				(type default)
			)
			(layer "B.SilkS")
		)
		(fp_line
			(start 0 0.635)
			(end 0 1.905)
			(stroke
				(width 0.1524)
				(type default)
			)
			(layer "B.SilkS")
		)
		(fp_line
			(start -2.54 1.4097)
			(end -2.54 1.1303)
			(stroke
				(width 0.1524)
				(type default)
			)
			(layer "B.SilkS")
		)
		(fp_line
			(start 0 3.175)
			(end 0 3.81)
			(stroke
				(width 0.1524)
				(type default)
			)
			(layer "B.SilkS")
		)
		(fp_line
			(start 0 3.81)
			(end -2.54 3.81)
			(stroke
				(width 0.1524)
				(type default)
			)
			(layer "B.SilkS")
		)
		(fp_line
			(start -2.54 3.81)
			(end -2.54 3.6703)
			(stroke
				(width 0.1524)
				(type default)
			)
			(layer "B.SilkS")
		)
		(fp_poly
			(pts
				(xy 2.285746 -0.762) (xy 2.285746 0.762) (xy 0.761746 0)
			)
			(stroke
				(width 0)
				(type default)
			)
			(fill yes)
			(layer "B.SilkS")
		)
		(fp_line
			(start 0 -1.27)
			(end 0 3.81)
			(stroke
				(width 0.1)
				(type default)
			)
			(layer "B.Fab")
		)
		(fp_line
			(start -2.54 -1.27)
			(end 0 -1.27)
			(stroke
				(width 0.1)
				(type default)
			)
			(layer "B.Fab")
		)
		(fp_line
			(start 0 3.81)
			(end -2.54 3.81)
			(stroke
				(width 0.1)
				(type default)
			)
			(layer "B.Fab")
		)
		(fp_line
			(start -2.54 3.81)
			(end -2.54 -1.27)
			(stroke
				(width 0.1)
				(type default)
			)
			(layer "B.Fab")
		)
		(fp_poly
			(pts
				(xy 0.761746 0) (xy 2.285746 -0.762) (xy 2.285746 0.762)
			)
			(stroke
				(width 0)
				(type default)
			)
			(fill yes)
			(layer "B.Fab")
		)
		(pad "1" thru_hole circle
			(at 0 0 270)
			(size 1.0033 1.0033)
			(drill 0.249936)
			(layers "*.Cu" "*.Mask")
			(remove_unused_layers no)
			(net "TDR_DIFF_100_BOT_DN")
			(clearance 0.10795)
			(padstack
				(mode front_inner_back)
				(layer "Inner"
					(shape circle)
					(size 0.8001 0.8001)
					(clearance 0.1524)
				)
				(layer "B.Cu"
					(shape circle)
					(size 1.0033 1.0033)
					(thermal_gap 0.10795)
					(clearance 0.10795)
				)
			)
		)
		(pad "2" thru_hole circle
			(at -2.54 0 270)
			(size 1.9939 1.9939)
			(drill 0.249936)
			(layers "*.Cu" "*.Mask")
			(remove_unused_layers no)
			(net "T1_GND")
			(clearance 0.10795)
			(padstack
				(mode front_inner_back)
				(layer "Inner"
					(shape circle)
					(size 0.8001 0.8001)
					(clearance 0.1524)
				)
				(layer "B.Cu"
					(shape circle)
					(size 1.9939 1.9939)
					(thermal_gap 0.10795)
					(clearance 0.10795)
				)
			)
		)
		(pad "3" thru_hole circle
			(at -2.54 2.54 270)
			(size 1.9939 1.9939)
			(drill 0.249936)
			(layers "*.Cu" "*.Mask")
			(remove_unused_layers no)
			(net "T1_GND")
			(clearance 0.10795)
			(padstack
				(mode front_inner_back)
				(layer "Inner"
					(shape circle)
					(size 0.8001 0.8001)
					(clearance 0.1524)
				)
				(layer "B.Cu"
					(shape circle)
					(size 1.9939 1.9939)
					(thermal_gap 0.10795)
					(clearance 0.10795)
				)
			)
		)
		(pad "4" thru_hole circle
			(at 0 2.54 270)
			(size 1.0033 1.0033)
			(drill 0.249936)
			(layers "*.Cu" "*.Mask")
			(remove_unused_layers no)
			(net "TDR_DIFF_100_BOT_DP")
			(clearance 0.10795)
			(padstack
				(mode front_inner_back)
				(layer "Inner"
					(shape circle)
					(size 0.8001 0.8001)
					(clearance 0.1524)
				)
				(layer "B.Cu"
					(shape circle)
					(size 1.0033 1.0033)
					(thermal_gap 0.10795)
					(clearance 0.10795)
				)
			)
		)
	)
	(footprint ""
		(layer "B.Cu")
		(at 169.66692 -51.399948 180)
		(property "Reference" "C1925"
			(at 0 0 0)
			(layer "B.SilkS")
			(hide yes)
			(effects
				(font
					(size 1.27 1.27)
				)
				(justify mirror)
			)
		)
		(property "Value" ""
			(at 0 0 0)
			(layer "B.Fab")
			(effects
				(font
					(size 1.27 1.27)
				)
				(justify mirror)
			)
		)
		(duplicate_pad_numbers_are_jumpers no)
		(fp_line
			(start 0.7874 0.4064)
			(end 0.7874 -0.4064)
			(stroke
				(width 0.1524)
				(type default)
			)
			(layer "B.SilkS")
		)
		(fp_line
			(start 0.7874 -0.4064)
			(end -0.7874 -0.4064)
			(stroke
				(width 0.1524)
				(type default)
			)
			(layer "B.SilkS")
		)
		(fp_line
			(start -0.7874 0.4064)
			(end 0.7874 0.4064)
			(stroke
				(width 0.1524)
				(type default)
			)
			(layer "B.SilkS")
		)
		(fp_line
			(start -0.7874 -0.4064)
			(end -0.7874 0.4064)
			(stroke
				(width 0.1524)
				(type default)
			)
			(layer "B.SilkS")
		)
		(fp_line
			(start 0.67945 0.3048)
			(end 0.67945 -0.305054)
			(stroke
				(width 0.1)
				(type default)
			)
			(layer "B.Fab")
		)
		(fp_line
			(start 0.67945 -0.305054)
			(end 0.12065 -0.305054)
			(stroke
				(width 0.1)
				(type default)
			)
			(layer "B.Fab")
		)
		(fp_line
			(start 0.12065 0.3048)
			(end 0.67945 0.3048)
			(stroke
				(width 0.1)
				(type default)
			)
			(layer "B.Fab")
		)
		(fp_line
			(start 0.12065 0.2794)
			(end 0.12065 0.3048)
			(stroke
				(width 0.1)
				(type default)
			)
			(layer "B.Fab")
		)
		(fp_line
			(start 0.12065 -0.2794)
			(end -0.12065 -0.2794)
			(stroke
				(width 0.1)
				(type default)
			)
			(layer "B.Fab")
		)
		(fp_line
			(start 0.12065 -0.305054)
			(end 0.12065 -0.2794)
			(stroke
				(width 0.1)
				(type default)
			)
			(layer "B.Fab")
		)
		(fp_line
			(start -0.120396 0.3048)
			(end -0.120396 0.2794)
			(stroke
				(width 0.1)
				(type default)
			)
			(layer "B.Fab")
		)
		(fp_line
			(start -0.120396 0.2794)
			(end 0.12065 0.2794)
			(stroke
				(width 0.1)
				(type default)
			)
			(layer "B.Fab")
		)
		(fp_line
			(start -0.12065 -0.2794)
			(end -0.12065 -0.3048)
			(stroke
				(width 0.1)
				(type default)
			)
			(layer "B.Fab")
		)
		(fp_line
			(start -0.12065 -0.3048)
			(end -0.67945 -0.3048)
			(stroke
				(width 0.1)
				(type default)
			)
			(layer "B.Fab")
		)
		(fp_line
			(start -0.67945 0.3048)
			(end -0.120396 0.3048)
			(stroke
				(width 0.1)
				(type default)
			)
			(layer "B.Fab")
		)
		(fp_line
			(start -0.67945 -0.3048)
			(end -0.67945 0.3048)
			(stroke
				(width 0.1)
				(type default)
			)
			(layer "B.Fab")
		)
		(pad "1" smd circle
			(at 0.40005 0)
			(size 0 0)
			(layers "B.Cu" "B.Mask" "B.Paste")
			(net "P3V3_M2_0")
		)
		(pad "2" smd circle
			(at -0.40005 0)
			(size 0 0)
			(layers "B.Cu" "B.Mask" "B.Paste")
			(net "GND")
		)
	)
	(footprint ""
		(layer "B.Cu")
		(at 405.129238 -193.04381 -90)
		(property "Reference" "R252"
			(at 0 0 90)
			(layer "B.SilkS")
			(hide yes)
			(effects
				(font
					(size 1.27 1.27)
				)
				(justify mirror)
			)
		)
		(property "Value" ""
			(at 0 0 90)
			(layer "B.Fab")
			(effects
				(font
					(size 1.27 1.27)
				)
				(justify mirror)
			)
		)
		(duplicate_pad_numbers_are_jumpers no)
		(fp_line
			(start -0.7874 0.4064)
			(end 0.7874 0.4064)
			(stroke
				(width 0.1524)
				(type default)
			)
			(layer "B.SilkS")
		)
		(fp_line
			(start 0.7874 0.4064)
			(end 0.7874 -0.4064)
			(stroke
				(width 0.1524)
				(type default)
			)
			(layer "B.SilkS")
		)
		(fp_line
			(start -0.7874 -0.4064)
			(end -0.7874 0.4064)
			(stroke
				(width 0.1524)
				(type default)
			)
			(layer "B.SilkS")
		)
		(fp_line
			(start 0.7874 -0.4064)
			(end -0.7874 -0.4064)
			(stroke
				(width 0.1524)
				(type default)
			)
			(layer "B.SilkS")
		)
		(fp_line
			(start -0.67945 0.3048)
			(end -0.120396 0.3048)
			(stroke
				(width 0.1)
				(type default)
			)
			(layer "B.Fab")
		)
		(fp_line
			(start -0.120396 0.3048)
			(end -0.120396 0.2794)
			(stroke
				(width 0.1)
				(type default)
			)
			(layer "B.Fab")
		)
		(fp_line
			(start 0.12065 0.3048)
			(end 0.67945 0.3048)
			(stroke
				(width 0.1)
				(type default)
			)
			(layer "B.Fab")
		)
		(fp_line
			(start 0.67945 0.3048)
			(end 0.67945 -0.305054)
			(stroke
				(width 0.1)
				(type default)
			)
			(layer "B.Fab")
		)
		(fp_line
			(start -0.120396 0.2794)
			(end 0.12065 0.2794)
			(stroke
				(width 0.1)
				(type default)
			)
			(layer "B.Fab")
		)
		(fp_line
			(start 0.12065 0.2794)
			(end 0.12065 0.3048)
			(stroke
				(width 0.1)
				(type default)
			)
			(layer "B.Fab")
		)
		(fp_line
			(start -0.12065 -0.2794)
			(end -0.12065 -0.3048)
			(stroke
				(width 0.1)
				(type default)
			)
			(layer "B.Fab")
		)
		(fp_line
			(start 0.12065 -0.2794)
			(end -0.12065 -0.2794)
			(stroke
				(width 0.1)
				(type default)
			)
			(layer "B.Fab")
		)
		(fp_line
			(start -0.67945 -0.3048)
			(end -0.67945 0.3048)
			(stroke
				(width 0.1)
				(type default)
			)
			(layer "B.Fab")
		)
		(fp_line
			(start -0.12065 -0.3048)
			(end -0.67945 -0.3048)
			(stroke
				(width 0.1)
				(type default)
			)
			(layer "B.Fab")
		)
		(fp_line
			(start 0.12065 -0.305054)
			(end 0.12065 -0.2794)
			(stroke
				(width 0.1)
				(type default)
			)
			(layer "B.Fab")
		)
		(fp_line
			(start 0.67945 -0.305054)
			(end 0.12065 -0.305054)
			(stroke
				(width 0.1)
				(type default)
			)
			(layer "B.Fab")
		)
		(pad "1" smd circle
			(at 0.40005 0 90)
			(size 0 0)
			(layers "B.Cu" "B.Mask" "B.Paste")
			(net "PVNN_TERM_CPU0")
		)
		(pad "2" smd circle
			(at -0.40005 0 90)
			(size 0 0)
			(layers "B.Cu" "B.Mask" "B.Paste")
			(net "PUD_PCH_BOOT_MODE_CPU0")
		)
	)
)
